# S9S_MB_2U (Grand Teton) — schematic netlist excerpt (pin names and nets, part order shuffled) for the footprints in the layout excerpt that follows; sources: Cadence DE-HDL packaged netlist, KiCad conversion of 03242023_DA0F0TMBIJ0_F0T_Motherboard_J_brd_V01_OCP.brd

R2845  Q_RES  33.2 1% CHIP  pkg 0402LF  page 213 : A = BMC_MONITER ; B = BMC_MONITER_R
C1288  Q_CAP  0.1UF 25V 10% X7R  pkg 0402  page 134 : A = P3V3_AUX ; B = GND

(kicad_pcb
	(version 20260206)
	(generator "pcbnew")
	(generator_version "10.0")
	(general
		(thickness 1.6)
		(legacy_teardrops no)
	)
	(paper "A4")
	(title_block
		(title "03242023_DA0F0TMBIJ0_F0T_Motherboard_J_brd_V01_OCP.brd")
		(comment 1 "Grand Teton / footprints 2103-2104 of 6105")
	)
	(layers
		(0 "F.Cu" signal "TOP")
		(4 "In1.Cu" signal "GND")
		(6 "In2.Cu" signal "IN1")
		(8 "In3.Cu" signal "GND1")
		(10 "In4.Cu" signal "IN2")
		(12 "In5.Cu" signal "GND2")
		(14 "In6.Cu" signal "IN3")
		(16 "In7.Cu" signal "GND3")
		(18 "In8.Cu" signal "VCC")
		(20 "In9.Cu" signal "VCC1")
		(22 "In10.Cu" signal "GND4")
		(24 "In11.Cu" signal "IN4")
		(26 "In12.Cu" signal "GND5")
		(28 "In13.Cu" signal "IN5")
		(30 "In14.Cu" signal "GND6")
		(32 "In15.Cu" signal "IN6")
		(34 "In16.Cu" signal "GND7")
		(2 "B.Cu" signal "BOTTOM")
		(9 "F.Adhes" user "F.Adhesive")
		(11 "B.Adhes" user "B.Adhesive")
		(13 "F.Paste" user "Package Geometry/Pastemask Top")
		(15 "B.Paste" user "Package Geometry/Pastemask Bottom")
		(5 "F.SilkS" user "Ref Des/Silkscreen Top")
		(7 "B.SilkS" user "Ref Des/Silkscreen Bottom")
		(1 "F.Mask" user "Board Geometry/Soldermask Top")
		(3 "B.Mask" user "Board Geometry/Soldermask Bottom")
		(17 "Dwgs.User" user "User.Drawings")
		(19 "Cmts.User" user "User.Comments")
		(21 "Eco1.User" user "User.Eco1")
		(23 "Eco2.User" user "User.Eco2")
		(25 "Edge.Cuts" user "Board Geometry/Outline")
		(27 "Margin" user)
		(31 "F.CrtYd" user "Package Geometry/Place Bound Top")
		(29 "B.CrtYd" user "Package Geometry/Place Bound Bottom")
		(35 "F.Fab" user "Ref Des/Assembly Top")
		(33 "B.Fab" user "Ref Des/Assembly Bottom")
	)
	(footprint ""
		(layer "F.Cu")
		(at 108.05668 -60.086748)
		(property "Reference" "C1288"
			(at 0 0 0)
			(layer "F.SilkS")
			(hide yes)
			(effects
				(font
					(size 1.27 1.27)
				)
			)
		)
		(property "Value" ""
			(at 0 0 0)
			(layer "F.Fab")
			(effects
				(font
					(size 1.27 1.27)
				)
			)
		)
		(duplicate_pad_numbers_are_jumpers no)
		(fp_line
			(start -0.7874 -0.4064)
			(end 0.7874 -0.4064)
			(stroke
				(width 0.1524)
				(type default)
			)
			(layer "F.SilkS")
		)
		(fp_line
			(start -0.7874 0.4064)
			(end -0.7874 -0.4064)
			(stroke
				(width 0.1524)
				(type default)
			)
			(layer "F.SilkS")
		)
		(fp_line
			(start 0.7874 -0.4064)
			(end 0.7874 0.4064)
			(stroke
				(width 0.1524)
				(type default)
			)
			(layer "F.SilkS")
		)
		(fp_line
			(start 0.7874 0.4064)
			(end -0.7874 0.4064)
			(stroke
				(width 0.1524)
				(type default)
			)
			(layer "F.SilkS")
		)
		(fp_line
			(start -0.67945 -0.305054)
			(end -0.12065 -0.305054)
			(stroke
				(width 0.1)
				(type default)
			)
			(layer "F.Fab")
		)
		(fp_line
			(start -0.67945 0.3048)
			(end -0.67945 -0.305054)
			(stroke
				(width 0.1)
				(type default)
			)
			(layer "F.Fab")
		)
		(fp_line
			(start -0.12065 -0.305054)
			(end -0.12065 -0.2794)
			(stroke
				(width 0.1)
				(type default)
			)
			(layer "F.Fab")
		)
		(fp_line
			(start -0.12065 -0.2794)
			(end 0.12065 -0.2794)
			(stroke
				(width 0.1)
				(type default)
			)
			(layer "F.Fab")
		)
		(fp_line
			(start -0.12065 0.2794)
			(end -0.12065 0.3048)
			(stroke
				(width 0.1)
				(type default)
			)
			(layer "F.Fab")
		)
		(fp_line
			(start -0.12065 0.3048)
			(end -0.67945 0.3048)
			(stroke
				(width 0.1)
				(type default)
			)
			(layer "F.Fab")
		)
		(fp_line
			(start 0.120396 0.2794)
			(end -0.12065 0.2794)
			(stroke
				(width 0.1)
				(type default)
			)
			(layer "F.Fab")
		)
		(fp_line
			(start 0.120396 0.3048)
			(end 0.120396 0.2794)
			(stroke
				(width 0.1)
				(type default)
			)
			(layer "F.Fab")
		)
		(fp_line
			(start 0.12065 -0.3048)
			(end 0.67945 -0.3048)
			(stroke
				(width 0.1)
				(type default)
			)
			(layer "F.Fab")
		)
		(fp_line
			(start 0.12065 -0.2794)
			(end 0.12065 -0.3048)
			(stroke
				(width 0.1)
				(type default)
			)
			(layer "F.Fab")
		)
		(fp_line
			(start 0.67945 -0.3048)
			(end 0.67945 0.3048)
			(stroke
				(width 0.1)
				(type default)
			)
			(layer "F.Fab")
		)
		(fp_line
			(start 0.67945 0.3048)
			(end 0.120396 0.3048)
			(stroke
				(width 0.1)
				(type default)
			)
			(layer "F.Fab")
		)
		(pad "1" smd circle
			(at -0.40005 0)
			(size 0 0)
			(layers "F.Cu" "F.Mask" "F.Paste")
			(net "P3V3_AUX")
		)
		(pad "2" smd circle
			(at 0.40005 0)
			(size 0 0)
			(layers "F.Cu" "F.Mask" "F.Paste")
			(net "GND")
		)
	)
	(footprint ""
		(layer "F.Cu")
		(at 160.83788 -105.755948 180)
		(property "Reference" "R2845"
			(at 0 0 180)
			(layer "F.SilkS")
			(hide yes)
			(effects
				(font
					(size 1.27 1.27)
				)
			)
		)
		(property "Value" ""
			(at 0 0 180)
			(layer "F.Fab")
			(effects
				(font
					(size 1.27 1.27)
				)
			)
		)
		(duplicate_pad_numbers_are_jumpers no)
		(fp_line
			(start 0.7874 0.4064)
			(end -0.7874 0.4064)
			(stroke
				(width 0.1524)
				(type default)
			)
			(layer "F.SilkS")
		)
		(fp_line
			(start 0.7874 -0.4064)
			(end 0.7874 0.4064)
			(stroke
				(width 0.1524)
				(type default)
			)
			(layer "F.SilkS")
		)
		(fp_line
			(start -0.7874 0.4064)
			(end -0.7874 -0.4064)
			(stroke
				(width 0.1524)
				(type default)
			)
			(layer "F.SilkS")
		)
		(fp_line
			(start -0.7874 -0.4064)
			(end 0.7874 -0.4064)
			(stroke
				(width 0.1524)
				(type default)
			)
			(layer "F.SilkS")
		)
		(fp_line
			(start 0.67945 0.3048)
			(end 0.120396 0.3048)
			(stroke
				(width 0.1)
				(type default)
			)
			(layer "F.Fab")
		)
		(fp_line
			(start 0.67945 -0.3048)
			(end 0.67945 0.3048)
			(stroke
				(width 0.1)
				(type default)
			)
			(layer "F.Fab")
		)
		(fp_line
			(start 0.12065 -0.2794)
			(end 0.12065 -0.3048)
			(stroke
				(width 0.1)
				(type default)
			)
			(layer "F.Fab")
		)
		(fp_line
			(start 0.12065 -0.3048)
			(end 0.67945 -0.3048)
			(stroke
				(width 0.1)
				(type default)
			)
			(layer "F.Fab")
		)
		(fp_line
			(start 0.120396 0.3048)
			(end 0.120396 0.2794)
			(stroke
				(width 0.1)
				(type default)
			)
			(layer "F.Fab")
		)
		(fp_line
			(start 0.120396 0.2794)
			(end -0.12065 0.2794)
			(stroke
				(width 0.1)
				(type default)
			)
			(layer "F.Fab")
		)
		(fp_line
			(start -0.12065 0.3048)
			(end -0.67945 0.3048)
			(stroke
				(width 0.1)
				(type default)
			)
			(layer "F.Fab")
		)
		(fp_line
			(start -0.12065 0.2794)
			(end -0.12065 0.3048)
			(stroke
				(width 0.1)
				(type default)
			)
			(layer "F.Fab")
		)
		(fp_line
			(start -0.12065 -0.2794)
			(end 0.12065 -0.2794)
			(stroke
				(width 0.1)
				(type default)
			)
			(layer "F.Fab")
		)
		(fp_line
			(start -0.12065 -0.305054)
			(end -0.12065 -0.2794)
			(stroke
				(width 0.1)
				(type default)
			)
			(layer "F.Fab")
		)
		(fp_line
			(start -0.67945 0.3048)
			(end -0.67945 -0.305054)
			(stroke
				(width 0.1)
				(type default)
			)
			(layer "F.Fab")
		)
		(fp_line
			(start -0.67945 -0.305054)
			(end -0.12065 -0.305054)
			(stroke
				(width 0.1)
				(type default)
			)
			(layer "F.Fab")
		)
		(pad "1" smd circle
			(at -0.40005 0 180)
			(size 0 0)
			(layers "F.Cu" "F.Mask" "F.Paste")
			(net "BMC_MONITER")
		)
		(pad "2" smd circle
			(at 0.40005 0 180)
			(size 0 0)
			(layers "F.Cu" "F.Mask" "F.Paste")
			(net "BMC_MONITER_R")
		)
	)
)
